(kicad_pcb
	(version 20241229)
	(generator "pcbnew")
	(generator_version "9.0")
	(general
		(thickness 1.61)
		(legacy_teardrops no)
	)
	(paper "A3")
	(title_block
		(title "RDIMM DDR5 Tester")
		(date "2026-05-21")
		(rev "2.2.0")
		(company "Antmicro")
		(comment 9 "footprints 57-61 of 796")
	)
	(layers
		(0 "F.Cu" signal)
		(4 "In1.Cu" power)
		(6 "In2.Cu" mixed)
		(8 "In3.Cu" power)
		(10 "In4.Cu" mixed)
		(12 "In5.Cu" power)
		(14 "In6.Cu" mixed)
		(16 "In7.Cu" power)
		(18 "In8.Cu" power)
		(20 "In9.Cu" mixed)
		(22 "In10.Cu" power)
		(2 "B.Cu" signal)
		(9 "F.Adhes" user "F.Adhesive")
		(11 "B.Adhes" user "B.Adhesive")
		(13 "F.Paste" user)
		(15 "B.Paste" user)
		(5 "F.SilkS" user "F.Silkscreen")
		(7 "B.SilkS" user "B.Silkscreen")
		(1 "F.Mask" user)
		(3 "B.Mask" user)
		(17 "Dwgs.User" user "User.Drawings")
		(19 "Cmts.User" user "User.Comments")
		(21 "Eco1.User" user "User.Eco1")
		(23 "Eco2.User" user "User.Eco2")
		(25 "Edge.Cuts" user)
		(27 "Margin" user)
		(31 "F.CrtYd" user "F.Courtyard")
		(29 "B.CrtYd" user "B.Courtyard")
		(35 "F.Fab" user)
		(33 "B.Fab" user)
	)
	(footprint "antmicro-footprints:R_0402_1005Metric"
		(layer "F.Cu")
		(at 143.724499 169.899 90)
		(descr "Resistor SMD 0402")
		(tags "resistor SMD 0402")
		(property "Reference" "R88"
			(at -3.301 -0.874499 90)
			(layer "F.SilkS")
			(effects
				(font
					(size 0.7 0.7)
					(thickness 0.15)
				)
				(justify left bottom)
			)
		)
		(property "Value" "R_0R_0402"
			(at -1.011843 1.772047 90)
			(layer "F.Fab")
			(effects
				(font
					(size 0.7 0.7)
					(thickness 0.15)
				)
				(justify left bottom)
			)
		)
		(property "Datasheet" "https://industrial.panasonic.com/cdbs/www-data/pdf/RDA0000/AOA0000C301.pdf"
			(at 0 0 90)
			(layer "F.Fab")
			(hide yes)
			(effects
				(font
					(size 1.27 1.27)
					(thickness 0.15)
				)
			)
		)
		(property "Manufacturer" "Panasonic"
			(at 0 0 90)
			(unlocked yes)
			(layer "F.Fab")
			(hide yes)
			(effects
				(font
					(size 1 1)
					(thickness 0.15)
				)
			)
		)
		(property "MPN" "ERJ2GE0R00X"
			(at 0 0 90)
			(unlocked yes)
			(layer "F.Fab")
			(hide yes)
			(effects
				(font
					(size 1 1)
					(thickness 0.15)
				)
			)
		)
		(property "Val" "0R"
			(at 0 0 90)
			(unlocked yes)
			(layer "F.Fab")
			(hide yes)
			(effects
				(font
					(size 1 1)
					(thickness 0.15)
				)
			)
		)
		(property "License" "Apache-2.0"
			(at 0 0 90)
			(unlocked yes)
			(layer "F.Fab")
			(hide yes)
			(effects
				(font
					(size 1 1)
					(thickness 0.15)
				)
			)
		)
		(property "Author" "Antmicro"
			(at 0 0 90)
			(unlocked yes)
			(layer "F.Fab")
			(hide yes)
			(effects
				(font
					(size 1 1)
					(thickness 0.15)
				)
			)
		)
		(property "Tolerance" "~"
			(at 0 0 90)
			(unlocked yes)
			(layer "F.Fab")
			(hide yes)
			(effects
				(font
					(size 1 1)
					(thickness 0.15)
				)
			)
		)
		(property "Current" "1A"
			(at 0 0 90)
			(unlocked yes)
			(layer "F.Fab")
			(hide yes)
			(effects
				(font
					(size 1 1)
					(thickness 0.15)
				)
			)
		)
		(sheetname "/Debug FTDI + VNA/")
		(sheetfile "debug-ftdi.kicad_sch")
		(attr smd)
		(fp_rect
			(start -0.925 -0.47)
			(end 0.925 0.47)
			(stroke
				(width 0.05)
				(type default)
			)
			(fill no)
			(layer "F.CrtYd")
		)
		(fp_rect
			(start -0.5 -0.25)
			(end 0.5 0.25)
			(stroke
				(width 0.15)
				(type solid)
			)
			(fill no)
			(layer "F.Fab")
		)
		(fp_text user "License: Apache-2.0"
			(at -0.95 5.169 90)
			(layer "F.Fab")
			(effects
				(font
					(size 0.7 0.7)
					(thickness 0.15)
				)
				(justify left bottom)
			)
		)
		(fp_text user "${REFERENCE}"
			(at -0.95 3.168 90)
			(layer "F.Fab")
			(effects
				(font
					(size 0.7 0.7)
					(thickness 0.15)
				)
				(justify left bottom)
			)
		)
		(fp_text user "Author: Antmicro"
			(at -0.95 4.169 90)
			(layer "F.Fab")
			(effects
				(font
					(size 0.7 0.7)
					(thickness 0.15)
				)
				(justify left bottom)
			)
		)
		(pad "1" smd roundrect
			(at -0.48 0 90)
			(size 0.59 0.64)
			(layers "F.Cu" "F.Mask" "F.Paste")
			(roundrect_rratio 0.25)
			(net 301 "Net-(U13-OE)")
			(pintype "passive")
		)
		(pad "2" smd roundrect
			(at 0.48 0 90)
			(size 0.59 0.64)
			(layers "F.Cu" "F.Mask" "F.Paste")
			(roundrect_rratio 0.25)
			(net 407 "/Debug FTDI + VNA/BDBUS3")
			(pintype "passive")
		)
	)
	(footprint "antmicro-footprints:F_0603_1608Metric"
		(layer "F.Cu")
		(at 243.4 119.6 90)
		(property "Reference" "F3"
			(at -0.3 -1.63 90)
			(layer "F.SilkS")
			(effects
				(font
					(size 0.7 0.7)
					(thickness 0.15)
				)
				(justify left top)
			)
		)
		(property "Value" "F_1.25A_0603"
			(at 0 1.7 90)
			(layer "F.Fab")
			(effects
				(font
					(size 0.7 0.7)
					(thickness 0.15)
				)
				(justify left top)
			)
		)
		(property "Datasheet" "https://www.littelfuse.com/~/media/electronics/datasheets/fuses/littelfuse_fuse_467_datasheet.pdf.pdf"
			(at 0 0 90)
			(layer "F.Fab")
			(hide yes)
			(effects
				(font
					(size 1.27 1.27)
					(thickness 0.15)
				)
			)
		)
		(property "MPN" "04671.25NR"
			(at 0 0 90)
			(unlocked yes)
			(layer "F.Fab")
			(hide yes)
			(effects
				(font
					(size 1 1)
					(thickness 0.15)
				)
			)
		)
		(property "Manufacturer" "Littelfuse"
			(at 0 0 90)
			(unlocked yes)
			(layer "F.Fab")
			(hide yes)
			(effects
				(font
					(size 1 1)
					(thickness 0.15)
				)
			)
		)
		(property "Author" "Antmicro"
			(at 0 0 90)
			(unlocked yes)
			(layer "F.Fab")
			(hide yes)
			(effects
				(font
					(size 1 1)
					(thickness 0.15)
				)
			)
		)
		(property "License" "Apache-2.0"
			(at 0 0 90)
			(unlocked yes)
			(layer "F.Fab")
			(hide yes)
			(effects
				(font
					(size 1 1)
					(thickness 0.15)
				)
			)
		)
		(sheetname "/Supply/")
		(sheetfile "supply.kicad_sch")
		(attr smd)
		(fp_line
			(start -0.15 -0.4)
			(end 0.15 -0.4)
			(stroke
				(width 0.15)
				(type solid)
			)
			(layer "F.SilkS")
		)
		(fp_line
			(start -0.15 0.4)
			(end 0.15 0.4)
			(stroke
				(width 0.15)
				(type solid)
			)
			(layer "F.SilkS")
		)
		(fp_rect
			(start -1.25 -0.65)
			(end 1.25 0.65)
			(stroke
				(width 0.05)
				(type solid)
			)
			(fill no)
			(layer "F.CrtYd")
		)
		(fp_line
			(start 0.8 -0.408)
			(end -0.803 -0.408)
			(stroke
				(width 0.15)
				(type solid)
			)
			(layer "F.Fab")
		)
		(fp_line
			(start 0.8 -0.408)
			(end 0.8 0.406)
			(stroke
				(width 0.15)
				(type solid)
			)
			(layer "F.Fab")
		)
		(fp_line
			(start 0.8 0.406)
			(end -0.803 0.406)
			(stroke
				(width 0.15)
				(type solid)
			)
			(layer "F.Fab")
		)
		(fp_line
			(start -0.803 0.406)
			(end -0.803 -0.408)
			(stroke
				(width 0.15)
				(type solid)
			)
			(layer "F.Fab")
		)
		(fp_text user "License: Apache-2.0"
			(at -1.653 5.9 90)
			(layer "F.Fab")
			(effects
				(font
					(size 0.7 0.7)
					(thickness 0.15)
				)
				(justify left bottom)
			)
		)
		(fp_text user "${REFERENCE}"
			(at -1.653 4.6 90)
			(layer "F.Fab")
			(effects
				(font
					(size 0.7 0.7)
					(thickness 0.15)
				)
				(justify left bottom)
			)
		)
		(fp_text user "Author: Antmicro"
			(at -1.653 3.162 90)
			(layer "F.Fab")
			(effects
				(font
					(size 0.7 0.7)
					(thickness 0.15)
				)
				(justify left bottom)
			)
		)
		(pad "1" smd roundrect
			(at -0.7 0 90)
			(size 0.8 1)
			(layers "F.Cu" "F.Mask" "F.Paste")
			(roundrect_rratio 0.2)
			(net 814 "Net-(Q29-D)")
			(pintype "passive")
		)
		(pad "2" smd roundrect
			(at 0.7 0 90)
			(size 0.8 1)
			(layers "F.Cu" "F.Mask" "F.Paste")
			(roundrect_rratio 0.2)
			(net 811 "/Supply/heater")
			(pintype "passive")
		)
	)
	(footprint "antmicro-footprints:L_0402_1005Metric"
		(layer "F.Cu")
		(at 121.025 148.61 180)
		(descr "Inductor SMD 0402")
		(tags "Inductor SMD 0402")
		(property "Reference" "L4"
			(at -5.385 -0.465 0)
			(layer "F.SilkS")
			(effects
				(font
					(size 0.7 0.7)
					(thickness 0.15)
				)
				(justify right bottom)
			)
		)
		(property "Value" "L_20n_0.35A_0402"
			(at 0 1.4 0)
			(layer "F.Fab")
			(effects
				(font
					(size 0.7 0.7)
					(thickness 0.15)
				)
				(justify right bottom)
			)
		)
		(property "Datasheet" "https://product.tdk.com/system/files/dam/doc/product/inductor/inductor/smd/catalog/inductor_automotive_high-frequency_mlg1005s_en.pdf?ref_disty=mouser"
			(at 0 0 180)
			(layer "F.Fab")
			(hide yes)
			(effects
				(font
					(size 1.27 1.27)
					(thickness 0.15)
				)
			)
		)
		(property "Val" "20n/0.35A"
			(at 0 0 180)
			(unlocked yes)
			(layer "F.Fab")
			(hide yes)
			(effects
				(font
					(size 1 1)
					(thickness 0.15)
				)
			)
		)
		(property "Manufacturer" "TDK"
			(at 0 0 180)
			(unlocked yes)
			(layer "F.Fab")
			(hide yes)
			(effects
				(font
					(size 1 1)
					(thickness 0.15)
				)
			)
		)
		(property "MPN" "MLG1005S20NJTD25"
			(at 0 0 180)
			(unlocked yes)
			(layer "F.Fab")
			(hide yes)
			(effects
				(font
					(size 1 1)
					(thickness 0.15)
				)
			)
		)
		(property "ISat" ""
			(at 0 0 180)
			(unlocked yes)
			(layer "F.Fab")
			(hide yes)
			(effects
				(font
					(size 1 1)
					(thickness 0.15)
				)
			)
		)
		(property "IMax" "0.35 A"
			(at 0 0 180)
			(unlocked yes)
			(layer "F.Fab")
			(hide yes)
			(effects
				(font
					(size 1 1)
					(thickness 0.15)
				)
			)
		)
		(property "Size" "1.0x0.5"
			(at 0 0 180)
			(unlocked yes)
			(layer "F.Fab")
			(hide yes)
			(effects
				(font
					(size 1 1)
					(thickness 0.15)
				)
			)
		)
		(property "Author" "Antmicro"
			(at 0 0 180)
			(unlocked yes)
			(layer "F.Fab")
			(hide yes)
			(effects
				(font
					(size 1 1)
					(thickness 0.15)
				)
			)
		)
		(property "License" "Apache-2.0"
			(at 0 0 180)
			(unlocked yes)
			(layer "F.Fab")
			(hide yes)
			(effects
				(font
					(size 1 1)
					(thickness 0.15)
				)
			)
		)
		(sheetname "/HDMI + SD Card/")
		(sheetfile "hdmi-sd-card.kicad_sch")
		(attr smd)
		(fp_rect
			(start -0.925 -0.47)
			(end 0.925 0.47)
			(stroke
				(width 0.05)
				(type default)
			)
			(fill no)
			(layer "F.CrtYd")
		)
		(fp_rect
			(start -0.499 -0.249)
			(end 0.499 0.249)
			(stroke
				(width 0.15)
				(type solid)
			)
			(fill no)
			(layer "F.Fab")
		)
		(fp_text user "${REFERENCE}"
			(at -0.932 3.168 180)
			(layer "F.Fab")
			(effects
				(font
					(size 0.7 0.7)
					(thickness 0.15)
				)
				(justify left bottom)
			)
		)
		(fp_text user "Author: Antmicro"
			(at -0.932 4.17 180)
			(layer "F.Fab")
			(effects
				(font
					(size 0.7 0.7)
					(thickness 0.15)
				)
				(justify left bottom)
			)
		)
		(fp_text user "License: Apache-2.0"
			(at -0.932 5.17 180)
			(layer "F.Fab")
			(effects
				(font
					(size 0.7 0.7)
					(thickness 0.15)
				)
				(justify left bottom)
			)
		)
		(pad "1" smd roundrect
			(at -0.48 0 180)
			(size 0.59 0.64)
			(layers "F.Cu" "F.Mask" "F.Paste")
			(roundrect_rratio 0.25)
			(net 342 "/FPGA MGT Interface/HDMI_IN.D2_N")
			(pintype "passive")
		)
		(pad "2" smd roundrect
			(at 0.48 0 180)
			(size 0.59 0.64)
			(layers "F.Cu" "F.Mask" "F.Paste")
			(roundrect_rratio 0.25)
			(net 674 "Net-(L4-Pad2)")
			(pintype "passive")
		)
	)
	(footprint "antmicro-footprints:R_0402_1005Metric"
		(layer "F.Cu")
		(at 253.5055 150.371 180)
		(descr "Resistor SMD 0402")
		(tags "resistor SMD 0402")
		(property "Reference" "R157"
			(at 0.8055 0.471 0)
			(layer "F.SilkS")
			(effects
				(font
					(size 0.7 0.7)
					(thickness 0.15)
				)
				(justify right bottom)
			)
		)
		(property "Value" "R_0R_0402"
			(at -1.011843 1.772047 0)
			(layer "F.Fab")
			(effects
				(font
					(size 0.7 0.7)
					(thickness 0.15)
				)
				(justify right bottom)
			)
		)
		(property "Datasheet" "https://industrial.panasonic.com/cdbs/www-data/pdf/RDA0000/AOA0000C301.pdf"
			(at 0 0 180)
			(layer "F.Fab")
			(hide yes)
			(effects
				(font
					(size 1.27 1.27)
					(thickness 0.15)
				)
			)
		)
		(property "Manufacturer" "Panasonic"
			(at 0 0 180)
			(unlocked yes)
			(layer "F.Fab")
			(hide yes)
			(effects
				(font
					(size 1 1)
					(thickness 0.15)
				)
			)
		)
		(property "MPN" "ERJ2GE0R00X"
			(at 0 0 180)
			(unlocked yes)
			(layer "F.Fab")
			(hide yes)
			(effects
				(font
					(size 1 1)
					(thickness 0.15)
				)
			)
		)
		(property "Val" "0R"
			(at 0 0 180)
			(unlocked yes)
			(layer "F.Fab")
			(hide yes)
			(effects
				(font
					(size 1 1)
					(thickness 0.15)
				)
			)
		)
		(property "License" "Apache-2.0"
			(at 0 0 180)
			(unlocked yes)
			(layer "F.Fab")
			(hide yes)
			(effects
				(font
					(size 1 1)
					(thickness 0.15)
				)
			)
		)
		(property "Author" "Antmicro"
			(at 0 0 180)
			(unlocked yes)
			(layer "F.Fab")
			(hide yes)
			(effects
				(font
					(size 1 1)
					(thickness 0.15)
				)
			)
		)
		(property "Tolerance" "~"
			(at 0 0 180)
			(unlocked yes)
			(layer "F.Fab")
			(hide yes)
			(effects
				(font
					(size 1 1)
					(thickness 0.15)
				)
			)
		)
		(property "Current" "1A"
			(at 0 0 180)
			(unlocked yes)
			(layer "F.Fab")
			(hide yes)
			(effects
				(font
					(size 1 1)
					(thickness 0.15)
				)
			)
		)
		(sheetname "/Supply/DC-DC IO/")
		(sheetfile "dc-dc-io.kicad_sch")
		(attr smd)
		(fp_rect
			(start -0.925 -0.47)
			(end 0.925 0.47)
			(stroke
				(width 0.05)
				(type default)
			)
			(fill no)
			(layer "F.CrtYd")
		)
		(fp_rect
			(start -0.5 -0.25)
			(end 0.5 0.25)
			(stroke
				(width 0.15)
				(type solid)
			)
			(fill no)
			(layer "F.Fab")
		)
		(fp_text user "${REFERENCE}"
			(at -0.95 3.168 180)
			(layer "F.Fab")
			(effects
				(font
					(size 0.7 0.7)
					(thickness 0.15)
				)
				(justify left bottom)
			)
		)
		(fp_text user "Author: Antmicro"
			(at -0.95 4.169 180)
			(layer "F.Fab")
			(effects
				(font
					(size 0.7 0.7)
					(thickness 0.15)
				)
				(justify left bottom)
			)
		)
		(fp_text user "License: Apache-2.0"
			(at -0.95 5.169 180)
			(layer "F.Fab")
			(effects
				(font
					(size 0.7 0.7)
					(thickness 0.15)
				)
				(justify left bottom)
			)
		)
		(pad "1" smd roundrect
			(at -0.48 0 180)
			(size 0.59 0.64)
			(layers "F.Cu" "F.Mask" "F.Paste")
			(roundrect_rratio 0.25)
			(net 715 "/Supply/DC-DC IO/FB6")
			(pintype "passive")
		)
		(pad "2" smd roundrect
			(at 0.48 0 180)
			(size 0.59 0.64)
			(layers "F.Cu" "F.Mask" "F.Paste")
			(roundrect_rratio 0.25)
			(net 46 "/Supply/DC-DC IO/5V_local")
			(pintype "passive")
		)
	)
	(footprint "antmicro-footprints:FB_0402_1005Metric"
		(layer "F.Cu")
		(at 120.1 145.61 180)
		(descr "Ferrite Bead SMD 0402")
		(tags "ferrite bead SMD 0402")
		(property "Reference" "FB7"
			(at -2.9 -0.365 0)
			(layer "F.SilkS")
			(effects
				(font
					(size 0.7 0.7)
					(thickness 0.15)
				)
				(justify right bottom)
			)
		)
		(property "Value" "FB_120Z_1.3A_Murata-BLM15PD_0402"
			(at 0 1.4 0)
			(layer "F.Fab")
			(effects
				(font
					(size 0.7 0.7)
					(thickness 0.15)
				)
				(justify right bottom)
			)
		)
		(property "Datasheet" "https://www.murata.com/en-us/products/productdata/8796740059166/ENFA0018.pdf"
			(at 0 0 180)
			(layer "F.Fab")
			(hide yes)
			(effects
				(font
					(size 1.27 1.27)
					(thickness 0.15)
				)
			)
		)
		(property "Val" "120Z/1.3A"
			(at 0 0 180)
			(unlocked yes)
			(layer "F.Fab")
			(hide yes)
			(effects
				(font
					(size 1 1)
					(thickness 0.15)
				)
			)
		)
		(property "MPN" "BLM15PD121SN1D"
			(at 0 0 180)
			(unlocked yes)
			(layer "F.Fab")
			(hide yes)
			(effects
				(font
					(size 1 1)
					(thickness 0.15)
				)
			)
		)
		(property "Manufacturer" "Murata"
			(at 0 0 180)
			(unlocked yes)
			(layer "F.Fab")
			(hide yes)
			(effects
				(font
					(size 1 1)
					(thickness 0.15)
				)
			)
		)
		(property "Current" ""
			(at 0 0 180)
			(unlocked yes)
			(layer "F.Fab")
			(hide yes)
			(effects
				(font
					(size 1 1)
					(thickness 0.15)
				)
			)
		)
		(property "Author" "Antmicro"
			(at 0 0 180)
			(unlocked yes)
			(layer "F.Fab")
			(hide yes)
			(effects
				(font
					(size 1 1)
					(thickness 0.15)
				)
			)
		)
		(property "License" "Apache-2.0"
			(at 0 0 180)
			(unlocked yes)
			(layer "F.Fab")
			(hide yes)
			(effects
				(font
					(size 1 1)
					(thickness 0.15)
				)
			)
		)
		(sheetname "/HDMI + SD Card/")
		(sheetfile "hdmi-sd-card.kicad_sch")
		(attr smd)
		(fp_rect
			(start -0.925 -0.47)
			(end 0.925 0.47)
			(stroke
				(width 0.05)
				(type default)
			)
			(fill no)
			(layer "F.CrtYd")
		)
		(fp_rect
			(start -0.5 -0.25)
			(end 0.5 0.25)
			(stroke
				(width 0.15)
				(type solid)
			)
			(fill no)
			(layer "F.Fab")
		)
		(fp_text user "License: Apache-2.0"
			(at -0.95 5.169 180)
			(layer "F.Fab")
			(effects
				(font
					(size 0.7 0.7)
					(thickness 0.15)
				)
				(justify left bottom)
			)
		)
		(fp_text user "Author: Antmicro"
			(at -0.95 4.169 180)
			(layer "F.Fab")
			(effects
				(font
					(size 0.7 0.7)
					(thickness 0.15)
				)
				(justify left bottom)
			)
		)
		(fp_text user "${REFERENCE}"
			(at -0.95 3.168 180)
			(layer "F.Fab")
			(effects
				(font
					(size 0.7 0.7)
					(thickness 0.15)
				)
				(justify left bottom)
			)
		)
		(pad "1" smd roundrect
			(at -0.48 0 180)
			(size 0.59 0.64)
			(layers "F.Cu" "F.Mask" "F.Paste")
			(roundrect_rratio 0.25)
			(net 151 "+3V3")
			(pintype "passive")
		)
		(pad "2" smd roundrect
			(at 0.48 0 180)
			(size 0.59 0.64)
			(layers "F.Cu" "F.Mask" "F.Paste")
			(roundrect_rratio 0.25)
			(net 322 "Net-(C300-Pad2)")
			(pintype "passive")
		)
	)
)
